# BASEBOARD_FAB2 (Tioga Pass) — schematic netlist excerpt (pin names and nets, part order shuffled) for the footprints in the layout excerpt that follows; sources: Cadence DE-HDL packaged netlist, KiCad conversion of Wiwynn_Tioga_Pass_MB.brd

C3P46  CAP_A  0.1UF 16V 10% X7R  pkg 0402V  page 196 : A = P3V3_STBY ; B = GND
C1M28  CAP_A  0.01UF 25V 10% X7R  pkg 0402V  page 113 : A = P3V3_STBY ; B = GND
R2R1  RES  10.0K 1% CHIP  pkg 0402  page 192 : A = P3V3_STBY ; B = PU_RST_PERST_BIT0

(kicad_pcb
	(version 20260206)
	(generator "pcbnew")
	(generator_version "10.0")
	(general
		(thickness 1.6)
		(legacy_teardrops no)
	)
	(paper "A4")
	(title_block
		(title "Wiwynn_Tioga_Pass_MB.brd")
		(comment 1 "Tioga Pass / footprints 4385-4387 of 4770")
	)
	(layers
		(0 "F.Cu" signal "TOP")
		(4 "In1.Cu" signal "L2GND")
		(6 "In2.Cu" signal "L3")
		(8 "In3.Cu" signal "L4GND")
		(10 "In4.Cu" signal "L5")
		(12 "In5.Cu" signal "L6GND")
		(14 "In6.Cu" signal "L7VCC")
		(16 "In7.Cu" signal "L8VCC")
		(18 "In8.Cu" signal "L9GND")
		(20 "In9.Cu" signal "L10")
		(22 "In10.Cu" signal "L11GND")
		(24 "In11.Cu" signal "L12")
		(26 "In12.Cu" signal "L13GND")
		(2 "B.Cu" signal "BOTTOM")
		(9 "F.Adhes" user "F.Adhesive")
		(11 "B.Adhes" user "B.Adhesive")
		(13 "F.Paste" user "Package Geometry/Pastemask Top")
		(15 "B.Paste" user "Package Geometry/Pastemask Bottom")
		(5 "F.SilkS" user "Ref Des/Silkscreen Top")
		(7 "B.SilkS" user "Ref Des/Silkscreen Bottom")
		(1 "F.Mask" user "Board Geometry/Soldermask Top")
		(3 "B.Mask" user "Board Geometry/Soldermask Bottom")
		(17 "Dwgs.User" user "User.Drawings")
		(19 "Cmts.User" user "User.Comments")
		(21 "Eco1.User" user "User.Eco1")
		(23 "Eco2.User" user "User.Eco2")
		(25 "Edge.Cuts" user "Board Geometry/Outline")
		(27 "Margin" user)
		(31 "F.CrtYd" user "Package Geometry/Place Bound Top")
		(29 "B.CrtYd" user "Package Geometry/Place Bound Bottom")
		(35 "F.Fab" user "Ref Des/Assembly Top")
		(33 "B.Fab" user "Ref Des/Assembly Bottom")
	)
	(footprint ""
		(layer "B.Cu")
		(at 499.618 -131.6228 -90)
		(property "Reference" "C1M28"
			(at 0 0 90)
			(layer "B.SilkS")
			(hide yes)
			(effects
				(font
					(size 1.27 1.27)
				)
				(justify mirror)
			)
		)
		(property "Value" ""
			(at 0 0 90)
			(layer "B.Fab")
			(effects
				(font
					(size 1.27 1.27)
				)
				(justify mirror)
			)
		)
		(duplicate_pad_numbers_are_jumpers no)
		(fp_poly
			(pts
				(xy -0.3048 -0.1016) (xy -0.3048 0.9906) (xy 0.3048 0.9906) (xy 0.3048 -0.1016)
			)
			(stroke
				(width 0)
				(type default)
			)
			(fill no)
			(layer "B.CrtYd")
		)
		(fp_line
			(start -0.3048 0.9906)
			(end -0.3048 -0.1016)
			(stroke
				(width 0.1)
				(type default)
			)
			(layer "B.Fab")
		)
		(fp_line
			(start 0.3048 0.9906)
			(end -0.3048 0.9906)
			(stroke
				(width 0.1)
				(type default)
			)
			(layer "B.Fab")
		)
		(fp_line
			(start -0.3048 -0.1016)
			(end 0.3048 -0.1016)
			(stroke
				(width 0.1)
				(type default)
			)
			(layer "B.Fab")
		)
		(fp_line
			(start 0.3048 -0.1016)
			(end 0.3048 0.9906)
			(stroke
				(width 0.1)
				(type default)
			)
			(layer "B.Fab")
		)
		(pad "1" smd rect
			(at 0 0 90)
			(size 0.508 0.508)
			(layers "B.Cu" "B.Mask" "B.Paste")
			(net "P3V3_STBY")
		)
		(pad "2" smd rect
			(at 0 0.889 90)
			(size 0.508 0.508)
			(layers "B.Cu" "B.Mask" "B.Paste")
			(net "GND")
		)
		(zone
			(layer "B.Cu")
			(hatch none 0.5)
			(connect_pads
				(clearance 0)
			)
			(min_thickness 0.25)
			(keepout
				(tracks not_allowed)
				(vias allowed)
				(pads allowed)
				(copperpour not_allowed)
				(footprints allowed)
			)
			(placement
				(enabled no)
				(sheetname "")
			)
			(fill
				(thermal_gap 0.5)
				(thermal_bridge_width 0.5)
				(island_removal_mode 0)
			)
			(polygon
				(pts
					(xy 498.983 -131.3688) (xy 498.983 -131.8768) (xy 499.364 -131.8768) (xy 499.364 -131.3688)
				)
			)
		)
		(zone
			(layer "B.Cu")
			(hatch none 0.5)
			(connect_pads
				(clearance 0)
			)
			(min_thickness 0.25)
			(keepout
				(tracks allowed)
				(vias not_allowed)
				(pads allowed)
				(copperpour not_allowed)
				(footprints allowed)
			)
			(placement
				(enabled no)
				(sheetname "")
			)
			(fill
				(thermal_gap 0.5)
				(thermal_bridge_width 0.5)
				(island_removal_mode 0)
			)
			(polygon
				(pts
					(xy 499.364 -131.3688) (xy 499.364 -131.8768) (xy 498.983 -131.8768) (xy 498.983 -131.3688)
				)
			)
		)
	)
	(footprint ""
		(layer "B.Cu")
		(at 422.91 -5.0165 180)
		(property "Reference" "C3P46"
			(at 0 0 0)
			(layer "B.SilkS")
			(hide yes)
			(effects
				(font
					(size 1.27 1.27)
				)
				(justify mirror)
			)
		)
		(property "Value" ""
			(at 0 0 0)
			(layer "B.Fab")
			(effects
				(font
					(size 1.27 1.27)
				)
				(justify mirror)
			)
		)
		(duplicate_pad_numbers_are_jumpers no)
		(fp_rect
			(start -0.3048 0.9906)
			(end 0.3048 -0.1016)
			(stroke
				(width 0)
				(type default)
			)
			(fill no)
			(layer "B.CrtYd")
		)
		(fp_line
			(start 0.3048 0.9906)
			(end -0.3048 0.9906)
			(stroke
				(width 0.1)
				(type default)
			)
			(layer "B.Fab")
		)
		(fp_line
			(start 0.3048 -0.1016)
			(end 0.3048 0.9906)
			(stroke
				(width 0.1)
				(type default)
			)
			(layer "B.Fab")
		)
		(fp_line
			(start -0.3048 0.9906)
			(end -0.3048 -0.1016)
			(stroke
				(width 0.1)
				(type default)
			)
			(layer "B.Fab")
		)
		(fp_line
			(start -0.3048 -0.1016)
			(end 0.3048 -0.1016)
			(stroke
				(width 0.1)
				(type default)
			)
			(layer "B.Fab")
		)
		(pad "1" smd rect
			(at 0 0)
			(size 0.508 0.508)
			(layers "B.Cu" "B.Mask" "B.Paste")
			(net "P3V3_STBY")
		)
		(pad "2" smd rect
			(at 0 0.889)
			(size 0.508 0.508)
			(layers "B.Cu" "B.Mask" "B.Paste")
			(net "GND")
		)
		(zone
			(layer "B.Cu")
			(hatch none 0.5)
			(connect_pads
				(clearance 0)
			)
			(min_thickness 0.25)
			(keepout
				(tracks not_allowed)
				(vias allowed)
				(pads allowed)
				(copperpour not_allowed)
				(footprints allowed)
			)
			(placement
				(enabled no)
				(sheetname "")
			)
			(fill
				(thermal_gap 0.5)
				(thermal_bridge_width 0.5)
				(island_removal_mode 0)
			)
			(polygon
				(pts
					(xy 423.164 -5.6515) (xy 422.656 -5.6515) (xy 422.656 -5.2705) (xy 423.164 -5.2705)
				)
			)
		)
		(zone
			(layer "B.Cu")
			(hatch none 0.5)
			(connect_pads
				(clearance 0)
			)
			(min_thickness 0.25)
			(keepout
				(tracks allowed)
				(vias not_allowed)
				(pads allowed)
				(copperpour not_allowed)
				(footprints allowed)
			)
			(placement
				(enabled no)
				(sheetname "")
			)
			(fill
				(thermal_gap 0.5)
				(thermal_bridge_width 0.5)
				(island_removal_mode 0)
			)
			(polygon
				(pts
					(xy 423.164 -5.6515) (xy 422.656 -5.6515) (xy 422.656 -5.2705) (xy 423.164 -5.2705)
				)
			)
		)
	)
	(footprint ""
		(layer "B.Cu")
		(at 376.936 -66.04 180)
		(property "Reference" "R2R1"
			(at 0 0 0)
			(layer "B.SilkS")
			(hide yes)
			(effects
				(font
					(size 1.27 1.27)
				)
				(justify mirror)
			)
		)
		(property "Value" ""
			(at 0 0 0)
			(layer "B.Fab")
			(effects
				(font
					(size 1.27 1.27)
				)
				(justify mirror)
			)
		)
		(duplicate_pad_numbers_are_jumpers no)
		(fp_poly
			(pts
				(xy 0.2794 -0.1016) (xy -0.2794 -0.1016) (xy -0.2794 0.9906) (xy 0.2794 0.9906)
			)
			(stroke
				(width 0)
				(type default)
			)
			(fill no)
			(layer "B.CrtYd")
		)
		(fp_line
			(start 0.2794 0.9906)
			(end -0.2794 0.9906)
			(stroke
				(width 0.1)
				(type default)
			)
			(layer "B.Fab")
		)
		(fp_line
			(start 0.2794 -0.1016)
			(end 0.2794 0.9906)
			(stroke
				(width 0.1)
				(type default)
			)
			(layer "B.Fab")
		)
		(fp_line
			(start -0.2794 0.9906)
			(end -0.2794 -0.1016)
			(stroke
				(width 0.1)
				(type default)
			)
			(layer "B.Fab")
		)
		(fp_line
			(start -0.2794 -0.1016)
			(end 0.2794 -0.1016)
			(stroke
				(width 0.1)
				(type default)
			)
			(layer "B.Fab")
		)
		(pad "1" smd rect
			(at 0 0)
			(size 0.508 0.508)
			(layers "B.Cu" "B.Mask" "B.Paste")
			(net "P3V3_STBY")
		)
		(pad "2" smd rect
			(at 0 0.889)
			(size 0.508 0.508)
			(layers "B.Cu" "B.Mask" "B.Paste")
			(net "PU_RST_PERST_BIT0")
		)
		(zone
			(layer "B.Cu")
			(hatch none 0.5)
			(connect_pads
				(clearance 0)
			)
			(min_thickness 0.25)
			(keepout
				(tracks not_allowed)
				(vias allowed)
				(pads allowed)
				(copperpour not_allowed)
				(footprints allowed)
			)
			(placement
				(enabled no)
				(sheetname "")
			)
			(fill
				(thermal_gap 0.5)
				(thermal_bridge_width 0.5)
				(island_removal_mode 0)
			)
			(polygon
				(pts
					(xy 376.682 -66.675) (xy 377.19 -66.675) (xy 377.19 -66.294) (xy 376.682 -66.294)
				)
			)
		)
		(zone
			(layer "B.Cu")
			(hatch none 0.5)
			(connect_pads
				(clearance 0)
			)
			(min_thickness 0.25)
			(keepout
				(tracks allowed)
				(vias not_allowed)
				(pads allowed)
				(copperpour not_allowed)
				(footprints allowed)
			)
			(placement
				(enabled no)
				(sheetname "")
			)
			(fill
				(thermal_gap 0.5)
				(thermal_bridge_width 0.5)
				(island_removal_mode 0)
			)
			(polygon
				(pts
					(xy 376.682 -66.294) (xy 377.19 -66.294) (xy 377.19 -66.675) (xy 376.682 -66.675)
				)
			)
		)
	)
)
